# T6G (Grand Teton) — schematic netlist excerpt (pin names and nets, part order shuffled) for the footprints in the layout excerpt that follows; sources: Cadence DE-HDL packaged netlist, KiCad conversion of 04192023_DAF0TMB3IC0_F0TG_MB_C_brd_V02_OCP.brd

R935  Q_RES  0 5% CHIP  pkg 0402LF  page 166 : A = BOOT_RDY_BUF_R_LED ; B = BOOT_RDY_BUF_LED
R484  Q_RES  0 5% CHIP  pkg 0402LF  page 27 : A = CPU0_XTRIG_L6 ; B = CPU0_XTRIG_R1_L6

(kicad_pcb
	(version 20260206)
	(generator "pcbnew")
	(generator_version "10.0")
	(general
		(thickness 1.6)
		(legacy_teardrops no)
	)
	(paper "A4")
	(title_block
		(title "04192023_DAF0TMB3IC0_F0TG_MB_C_brd_V02_OCP.brd")
		(comment 1 "Grand Teton / footprints 2590-2591 of 8354")
	)
	(layers
		(0 "F.Cu" signal "TOP")
		(4 "In1.Cu" signal "GND")
		(6 "In2.Cu" signal "IN1")
		(8 "In3.Cu" signal "GND1")
		(10 "In4.Cu" signal "IN2")
		(12 "In5.Cu" signal "GND2")
		(14 "In6.Cu" signal "IN3")
		(16 "In7.Cu" signal "GND3")
		(18 "In8.Cu" signal "VCC")
		(20 "In9.Cu" signal "VCC1")
		(22 "In10.Cu" signal "GND4")
		(24 "In11.Cu" signal "IN4")
		(26 "In12.Cu" signal "GND5")
		(28 "In13.Cu" signal "IN5")
		(30 "In14.Cu" signal "GND6")
		(32 "In15.Cu" signal "IN6")
		(34 "In16.Cu" signal "GND7")
		(2 "B.Cu" signal "BOTTOM")
		(9 "F.Adhes" user "F.Adhesive")
		(11 "B.Adhes" user "B.Adhesive")
		(13 "F.Paste" user "Package Geometry/Pastemask Top")
		(15 "B.Paste" user "Package Geometry/Pastemask Bottom")
		(5 "F.SilkS" user "Ref Des/Silkscreen Top")
		(7 "B.SilkS" user "Ref Des/Silkscreen Bottom")
		(1 "F.Mask" user "Board Geometry/Soldermask Top")
		(3 "B.Mask" user "Board Geometry/Soldermask Bottom")
		(17 "Dwgs.User" user "User.Drawings")
		(19 "Cmts.User" user "User.Comments")
		(21 "Eco1.User" user "User.Eco1")
		(23 "Eco2.User" user "User.Eco2")
		(25 "Edge.Cuts" user "Board Geometry/Outline")
		(27 "Margin" user)
		(31 "F.CrtYd" user "Package Geometry/Place Bound Top")
		(29 "B.CrtYd" user "Package Geometry/Place Bound Bottom")
		(35 "F.Fab" user "Ref Des/Assembly Top")
		(33 "B.Fab" user "Ref Des/Assembly Bottom")
	)
	(footprint ""
		(layer "F.Cu")
		(at 339.699346 -23.897336 -90)
		(property "Reference" "R935"
			(at 0 0 270)
			(layer "F.SilkS")
			(hide yes)
			(effects
				(font
					(size 1.27 1.27)
				)
			)
		)
		(property "Value" ""
			(at 0 0 270)
			(layer "F.Fab")
			(effects
				(font
					(size 1.27 1.27)
				)
			)
		)
		(duplicate_pad_numbers_are_jumpers no)
		(fp_line
			(start -0.7874 0.4064)
			(end -0.7874 -0.4064)
			(stroke
				(width 0.1524)
				(type default)
			)
			(layer "F.SilkS")
		)
		(fp_line
			(start 0.7874 0.4064)
			(end -0.7874 0.4064)
			(stroke
				(width 0.1524)
				(type default)
			)
			(layer "F.SilkS")
		)
		(fp_line
			(start -0.7874 -0.4064)
			(end 0.7874 -0.4064)
			(stroke
				(width 0.1524)
				(type default)
			)
			(layer "F.SilkS")
		)
		(fp_line
			(start 0.7874 -0.4064)
			(end 0.7874 0.4064)
			(stroke
				(width 0.1524)
				(type default)
			)
			(layer "F.SilkS")
		)
		(fp_line
			(start -0.67945 0.3048)
			(end -0.67945 -0.305054)
			(stroke
				(width 0.1)
				(type default)
			)
			(layer "F.Fab")
		)
		(fp_line
			(start -0.12065 0.3048)
			(end -0.67945 0.3048)
			(stroke
				(width 0.1)
				(type default)
			)
			(layer "F.Fab")
		)
		(fp_line
			(start 0.120396 0.3048)
			(end 0.120396 0.2794)
			(stroke
				(width 0.1)
				(type default)
			)
			(layer "F.Fab")
		)
		(fp_line
			(start 0.67945 0.3048)
			(end 0.120396 0.3048)
			(stroke
				(width 0.1)
				(type default)
			)
			(layer "F.Fab")
		)
		(fp_line
			(start -0.12065 0.2794)
			(end -0.12065 0.3048)
			(stroke
				(width 0.1)
				(type default)
			)
			(layer "F.Fab")
		)
		(fp_line
			(start 0.120396 0.2794)
			(end -0.12065 0.2794)
			(stroke
				(width 0.1)
				(type default)
			)
			(layer "F.Fab")
		)
		(fp_line
			(start -0.12065 -0.2794)
			(end 0.12065 -0.2794)
			(stroke
				(width 0.1)
				(type default)
			)
			(layer "F.Fab")
		)
		(fp_line
			(start 0.12065 -0.2794)
			(end 0.12065 -0.3048)
			(stroke
				(width 0.1)
				(type default)
			)
			(layer "F.Fab")
		)
		(fp_line
			(start 0.12065 -0.3048)
			(end 0.67945 -0.3048)
			(stroke
				(width 0.1)
				(type default)
			)
			(layer "F.Fab")
		)
		(fp_line
			(start 0.67945 -0.3048)
			(end 0.67945 0.3048)
			(stroke
				(width 0.1)
				(type default)
			)
			(layer "F.Fab")
		)
		(fp_line
			(start -0.67945 -0.305054)
			(end -0.12065 -0.305054)
			(stroke
				(width 0.1)
				(type default)
			)
			(layer "F.Fab")
		)
		(fp_line
			(start -0.12065 -0.305054)
			(end -0.12065 -0.2794)
			(stroke
				(width 0.1)
				(type default)
			)
			(layer "F.Fab")
		)
		(pad "1" smd circle
			(at -0.40005 0 270)
			(size 0 0)
			(layers "F.Cu" "F.Mask" "F.Paste")
			(net "BOOT_RDY_BUF_R_LED")
		)
		(pad "2" smd circle
			(at 0.40005 0 270)
			(size 0 0)
			(layers "F.Cu" "F.Mask" "F.Paste")
			(net "BOOT_RDY_BUF_LED")
		)
	)
	(footprint ""
		(layer "F.Cu")
		(at 350.44761 -62.634876 180)
		(property "Reference" "R484"
			(at 0 0 180)
			(layer "F.SilkS")
			(hide yes)
			(effects
				(font
					(size 1.27 1.27)
				)
			)
		)
		(property "Value" ""
			(at 0 0 180)
			(layer "F.Fab")
			(effects
				(font
					(size 1.27 1.27)
				)
			)
		)
		(duplicate_pad_numbers_are_jumpers no)
		(fp_line
			(start 0.7874 0.4064)
			(end -0.7874 0.4064)
			(stroke
				(width 0.1524)
				(type default)
			)
			(layer "F.SilkS")
		)
		(fp_line
			(start 0.7874 -0.4064)
			(end 0.7874 0.4064)
			(stroke
				(width 0.1524)
				(type default)
			)
			(layer "F.SilkS")
		)
		(fp_line
			(start -0.7874 0.4064)
			(end -0.7874 -0.4064)
			(stroke
				(width 0.1524)
				(type default)
			)
			(layer "F.SilkS")
		)
		(fp_line
			(start -0.7874 -0.4064)
			(end 0.7874 -0.4064)
			(stroke
				(width 0.1524)
				(type default)
			)
			(layer "F.SilkS")
		)
		(fp_line
			(start 0.67945 0.3048)
			(end 0.120396 0.3048)
			(stroke
				(width 0.1)
				(type default)
			)
			(layer "F.Fab")
		)
		(fp_line
			(start 0.67945 -0.3048)
			(end 0.67945 0.3048)
			(stroke
				(width 0.1)
				(type default)
			)
			(layer "F.Fab")
		)
		(fp_line
			(start 0.12065 -0.2794)
			(end 0.12065 -0.3048)
			(stroke
				(width 0.1)
				(type default)
			)
			(layer "F.Fab")
		)
		(fp_line
			(start 0.12065 -0.3048)
			(end 0.67945 -0.3048)
			(stroke
				(width 0.1)
				(type default)
			)
			(layer "F.Fab")
		)
		(fp_line
			(start 0.120396 0.3048)
			(end 0.120396 0.2794)
			(stroke
				(width 0.1)
				(type default)
			)
			(layer "F.Fab")
		)
		(fp_line
			(start 0.120396 0.2794)
			(end -0.12065 0.2794)
			(stroke
				(width 0.1)
				(type default)
			)
			(layer "F.Fab")
		)
		(fp_line
			(start -0.12065 0.3048)
			(end -0.67945 0.3048)
			(stroke
				(width 0.1)
				(type default)
			)
			(layer "F.Fab")
		)
		(fp_line
			(start -0.12065 0.2794)
			(end -0.12065 0.3048)
			(stroke
				(width 0.1)
				(type default)
			)
			(layer "F.Fab")
		)
		(fp_line
			(start -0.12065 -0.2794)
			(end 0.12065 -0.2794)
			(stroke
				(width 0.1)
				(type default)
			)
			(layer "F.Fab")
		)
		(fp_line
			(start -0.12065 -0.305054)
			(end -0.12065 -0.2794)
			(stroke
				(width 0.1)
				(type default)
			)
			(layer "F.Fab")
		)
		(fp_line
			(start -0.67945 0.3048)
			(end -0.67945 -0.305054)
			(stroke
				(width 0.1)
				(type default)
			)
			(layer "F.Fab")
		)
		(fp_line
			(start -0.67945 -0.305054)
			(end -0.12065 -0.305054)
			(stroke
				(width 0.1)
				(type default)
			)
			(layer "F.Fab")
		)
		(pad "1" smd circle
			(at -0.40005 0 180)
			(size 0 0)
			(layers "F.Cu" "F.Mask" "F.Paste")
			(net "CPU0_XTRIG_L6")
		)
		(pad "2" smd circle
			(at 0.40005 0 180)
			(size 0 0)
			(layers "F.Cu" "F.Mask" "F.Paste")
			(net "CPU0_XTRIG_R1_L6")
		)
	)
)
